# T6G (Grand Teton) — schematic netlist excerpt (pin names and nets, part order shuffled) for the footprints in the layout excerpt that follows; sources: Cadence DE-HDL packaged netlist, KiCad conversion of 04192023_DAF0TMB3IC0_F0TG_MB_C_brd_V02_OCP.brd

PC95_1  Q_CAP  22UF 16V 20% X6S  pkg C0805  page 201 : A = SW_P12V_AUX_PVDDCR_CPU1_P0_FLT ; B = GND
C1012  Q_CAP  0.1UF 10V 10% X7S  pkg C0201  page 312 : A = P0V9_CPU0_RT_2D ; B = GND
C2345  Q_CAP  22UF 4V 20% X6S  pkg C0402  page 73 : A = PVDDCR_CPU0_P1 ; B = GND
PC181_3  Q_CAP  22UF 16V 20% X6S  pkg C0805  page 206 : A = SW_P12V_AUX_PVDDIO_P0_FLT ; B = GND

(kicad_pcb
	(version 20260206)
	(generator "pcbnew")
	(generator_version "10.0")
	(general
		(thickness 1.6)
		(legacy_teardrops no)
	)
	(paper "A4")
	(title_block
		(title "04192023_DAF0TMB3IC0_F0TG_MB_C_brd_V02_OCP.brd")
		(comment 1 "Grand Teton / footprints 6304-6307 of 8354")
	)
	(layers
		(0 "F.Cu" signal "TOP")
		(4 "In1.Cu" signal "GND")
		(6 "In2.Cu" signal "IN1")
		(8 "In3.Cu" signal "GND1")
		(10 "In4.Cu" signal "IN2")
		(12 "In5.Cu" signal "GND2")
		(14 "In6.Cu" signal "IN3")
		(16 "In7.Cu" signal "GND3")
		(18 "In8.Cu" signal "VCC")
		(20 "In9.Cu" signal "VCC1")
		(22 "In10.Cu" signal "GND4")
		(24 "In11.Cu" signal "IN4")
		(26 "In12.Cu" signal "GND5")
		(28 "In13.Cu" signal "IN5")
		(30 "In14.Cu" signal "GND6")
		(32 "In15.Cu" signal "IN6")
		(34 "In16.Cu" signal "GND7")
		(2 "B.Cu" signal "BOTTOM")
		(9 "F.Adhes" user "F.Adhesive")
		(11 "B.Adhes" user "B.Adhesive")
		(13 "F.Paste" user "Package Geometry/Pastemask Top")
		(15 "B.Paste" user "Package Geometry/Pastemask Bottom")
		(5 "F.SilkS" user "Ref Des/Silkscreen Top")
		(7 "B.SilkS" user "Ref Des/Silkscreen Bottom")
		(1 "F.Mask" user "Board Geometry/Soldermask Top")
		(3 "B.Mask" user "Board Geometry/Soldermask Bottom")
		(17 "Dwgs.User" user "User.Drawings")
		(19 "Cmts.User" user "User.Comments")
		(21 "Eco1.User" user "User.Eco1")
		(23 "Eco2.User" user "User.Eco2")
		(25 "Edge.Cuts" user "Board Geometry/Outline")
		(27 "Margin" user)
		(31 "F.CrtYd" user "Package Geometry/Place Bound Top")
		(29 "B.CrtYd" user "Package Geometry/Place Bound Bottom")
		(35 "F.Fab" user "Ref Des/Assembly Top")
		(33 "B.Fab" user "Ref Des/Assembly Bottom")
	)
	(footprint ""
		(layer "B.Cu")
		(at 119.801386 -249.368564)
		(property "Reference" "C2345"
			(at 0 0 0)
			(layer "B.SilkS")
			(hide yes)
			(effects
				(font
					(size 1.27 1.27)
				)
				(justify mirror)
			)
		)
		(property "Value" ""
			(at 0 0 0)
			(layer "B.Fab")
			(effects
				(font
					(size 1.27 1.27)
				)
				(justify mirror)
			)
		)
		(duplicate_pad_numbers_are_jumpers no)
		(fp_line
			(start -0.7874 -0.4064)
			(end -0.7874 0.4064)
			(stroke
				(width 0.1524)
				(type default)
			)
			(layer "B.SilkS")
		)
		(fp_line
			(start -0.7874 0.4064)
			(end 0.7874 0.4064)
			(stroke
				(width 0.1524)
				(type default)
			)
			(layer "B.SilkS")
		)
		(fp_line
			(start 0.7874 -0.4064)
			(end -0.7874 -0.4064)
			(stroke
				(width 0.1524)
				(type default)
			)
			(layer "B.SilkS")
		)
		(fp_line
			(start 0.7874 0.4064)
			(end 0.7874 -0.4064)
			(stroke
				(width 0.1524)
				(type default)
			)
			(layer "B.SilkS")
		)
		(fp_line
			(start -0.67945 -0.3048)
			(end -0.67945 0.3048)
			(stroke
				(width 0.1)
				(type default)
			)
			(layer "B.Fab")
		)
		(fp_line
			(start -0.67945 0.3048)
			(end -0.120396 0.3048)
			(stroke
				(width 0.1)
				(type default)
			)
			(layer "B.Fab")
		)
		(fp_line
			(start -0.12065 -0.3048)
			(end -0.67945 -0.3048)
			(stroke
				(width 0.1)
				(type default)
			)
			(layer "B.Fab")
		)
		(fp_line
			(start -0.12065 -0.2794)
			(end -0.12065 -0.3048)
			(stroke
				(width 0.1)
				(type default)
			)
			(layer "B.Fab")
		)
		(fp_line
			(start -0.120396 0.2794)
			(end 0.12065 0.2794)
			(stroke
				(width 0.1)
				(type default)
			)
			(layer "B.Fab")
		)
		(fp_line
			(start -0.120396 0.3048)
			(end -0.120396 0.2794)
			(stroke
				(width 0.1)
				(type default)
			)
			(layer "B.Fab")
		)
		(fp_line
			(start 0.12065 -0.305054)
			(end 0.12065 -0.2794)
			(stroke
				(width 0.1)
				(type default)
			)
			(layer "B.Fab")
		)
		(fp_line
			(start 0.12065 -0.2794)
			(end -0.12065 -0.2794)
			(stroke
				(width 0.1)
				(type default)
			)
			(layer "B.Fab")
		)
		(fp_line
			(start 0.12065 0.2794)
			(end 0.12065 0.3048)
			(stroke
				(width 0.1)
				(type default)
			)
			(layer "B.Fab")
		)
		(fp_line
			(start 0.12065 0.3048)
			(end 0.67945 0.3048)
			(stroke
				(width 0.1)
				(type default)
			)
			(layer "B.Fab")
		)
		(fp_line
			(start 0.67945 -0.305054)
			(end 0.12065 -0.305054)
			(stroke
				(width 0.1)
				(type default)
			)
			(layer "B.Fab")
		)
		(fp_line
			(start 0.67945 0.3048)
			(end 0.67945 -0.305054)
			(stroke
				(width 0.1)
				(type default)
			)
			(layer "B.Fab")
		)
		(pad "1" smd circle
			(at 0.40005 0 180)
			(size 0 0)
			(layers "B.Cu" "B.Mask" "B.Paste")
			(net "PVDDCR_CPU0_P1")
		)
		(pad "2" smd circle
			(at -0.40005 0 180)
			(size 0 0)
			(layers "B.Cu" "B.Mask" "B.Paste")
			(net "GND")
		)
	)
	(footprint ""
		(layer "B.Cu")
		(at 284.82417 -346.784168 90)
		(property "Reference" "PC181_3"
			(at 0 0 90)
			(layer "B.SilkS")
			(hide yes)
			(effects
				(font
					(size 1.27 1.27)
				)
				(justify mirror)
			)
		)
		(property "Value" ""
			(at 0 0 90)
			(layer "B.Fab")
			(effects
				(font
					(size 1.27 1.27)
				)
				(justify mirror)
			)
		)
		(duplicate_pad_numbers_are_jumpers no)
		(fp_line
			(start 1.524 -0.762)
			(end -1.524 -0.762)
			(stroke
				(width 0.1524)
				(type default)
			)
			(layer "B.SilkS")
		)
		(fp_line
			(start -1.524 -0.762)
			(end -1.524 0.762)
			(stroke
				(width 0.1524)
				(type default)
			)
			(layer "B.SilkS")
		)
		(fp_line
			(start 1.524 0.762)
			(end 1.524 -0.762)
			(stroke
				(width 0.1524)
				(type default)
			)
			(layer "B.SilkS")
		)
		(fp_line
			(start -1.524 0.762)
			(end 1.524 0.762)
			(stroke
				(width 0.1524)
				(type default)
			)
			(layer "B.SilkS")
		)
		(fp_line
			(start 1.1049 -0.724916)
			(end 1.1049 0.724916)
			(stroke
				(width 0.1)
				(type default)
			)
			(layer "B.Fab")
		)
		(fp_line
			(start -1.1049 -0.724916)
			(end 1.1049 -0.724916)
			(stroke
				(width 0.1)
				(type default)
			)
			(layer "B.Fab")
		)
		(fp_line
			(start 1.1049 0.724916)
			(end -1.1049 0.724916)
			(stroke
				(width 0.1)
				(type default)
			)
			(layer "B.Fab")
		)
		(fp_line
			(start -1.1049 0.724916)
			(end -1.1049 -0.724916)
			(stroke
				(width 0.1)
				(type default)
			)
			(layer "B.Fab")
		)
		(pad "1" smd rect
			(at 0.889 0 90)
			(size 1.016 1.27)
			(layers "B.Cu" "B.Mask" "B.Paste")
			(net "SW_P12V_AUX_PVDDIO_P0_FLT")
		)
		(pad "2" smd rect
			(at -0.889 0 90)
			(size 1.016 1.27)
			(layers "B.Cu" "B.Mask" "B.Paste")
			(net "GND")
		)
	)
	(footprint ""
		(layer "B.Cu")
		(at 336.180684 -338.913216 -90)
		(property "Reference" "PC95_1"
			(at 0 0 90)
			(layer "B.SilkS")
			(hide yes)
			(effects
				(font
					(size 1.27 1.27)
				)
				(justify mirror)
			)
		)
		(property "Value" ""
			(at 0 0 90)
			(layer "B.Fab")
			(effects
				(font
					(size 1.27 1.27)
				)
				(justify mirror)
			)
		)
		(duplicate_pad_numbers_are_jumpers no)
		(fp_line
			(start -1.524 0.762)
			(end 1.524 0.762)
			(stroke
				(width 0.1524)
				(type default)
			)
			(layer "B.SilkS")
		)
		(fp_line
			(start 1.524 0.762)
			(end 1.524 -0.762)
			(stroke
				(width 0.1524)
				(type default)
			)
			(layer "B.SilkS")
		)
		(fp_line
			(start -1.524 -0.762)
			(end -1.524 0.762)
			(stroke
				(width 0.1524)
				(type default)
			)
			(layer "B.SilkS")
		)
		(fp_line
			(start 1.524 -0.762)
			(end -1.524 -0.762)
			(stroke
				(width 0.1524)
				(type default)
			)
			(layer "B.SilkS")
		)
		(fp_line
			(start -1.1049 0.724916)
			(end -1.1049 -0.724916)
			(stroke
				(width 0.1)
				(type default)
			)
			(layer "B.Fab")
		)
		(fp_line
			(start 1.1049 0.724916)
			(end -1.1049 0.724916)
			(stroke
				(width 0.1)
				(type default)
			)
			(layer "B.Fab")
		)
		(fp_line
			(start -1.1049 -0.724916)
			(end 1.1049 -0.724916)
			(stroke
				(width 0.1)
				(type default)
			)
			(layer "B.Fab")
		)
		(fp_line
			(start 1.1049 -0.724916)
			(end 1.1049 0.724916)
			(stroke
				(width 0.1)
				(type default)
			)
			(layer "B.Fab")
		)
		(pad "1" smd rect
			(at 0.889 0 270)
			(size 1.016 1.27)
			(layers "B.Cu" "B.Mask" "B.Paste")
			(net "SW_P12V_AUX_PVDDCR_CPU1_P0_FLT")
		)
		(pad "2" smd rect
			(at -0.889 0 270)
			(size 1.016 1.27)
			(layers "B.Cu" "B.Mask" "B.Paste")
			(net "GND")
		)
	)
	(footprint ""
		(layer "B.Cu")
		(at 382.618488 -396.393162 -90)
		(property "Reference" "C1012"
			(at 0 0 90)
			(layer "B.SilkS")
			(hide yes)
			(effects
				(font
					(size 1.27 1.27)
				)
				(justify mirror)
			)
		)
		(property "Value" ""
			(at 0 0 90)
			(layer "B.Fab")
			(effects
				(font
					(size 1.27 1.27)
				)
				(justify mirror)
			)
		)
		(duplicate_pad_numbers_are_jumpers no)
		(fp_line
			(start -0.299974 0.150114)
			(end 0.299974 0.150114)
			(stroke
				(width 0.1)
				(type default)
			)
			(layer "B.Fab")
		)
		(fp_line
			(start 0.299974 0.150114)
			(end 0.299974 -0.150114)
			(stroke
				(width 0.1)
				(type default)
			)
			(layer "B.Fab")
		)
		(fp_line
			(start -0.299974 -0.150114)
			(end -0.299974 0.150114)
			(stroke
				(width 0.1)
				(type default)
			)
			(layer "B.Fab")
		)
		(fp_line
			(start 0.299974 -0.150114)
			(end -0.299974 -0.150114)
			(stroke
				(width 0.1)
				(type default)
			)
			(layer "B.Fab")
		)
		(pad "1" smd rect
			(at 0.2667 0 90)
			(size 0.3048 0.381)
			(layers "B.Cu" "B.Mask" "B.Paste")
			(net "P0V9_CPU0_RT_2D")
		)
		(pad "2" smd rect
			(at -0.2667 0 90)
			(size 0.3048 0.381)
			(layers "B.Cu" "B.Mask" "B.Paste")
			(net "GND")
		)
	)
)
